(kicad_pcb
	(version 20260206)
	(generator "pcbnew")
	(generator_version "10.0")
	(general
		(thickness 1.6)
		(legacy_teardrops no)
	)
	(paper "A4")
	(title_block
		(title "01162023_DA0F0TEBIF0_F0T_Expander_BD_F_brd_V02_OCP.brd")
		(comment 1 "Grand Teton / footprints 5273-5280 of 9728")
	)
	(layers
		(0 "F.Cu" signal "TOP")
		(4 "In1.Cu" signal "GND")
		(6 "In2.Cu" signal "VCC")
		(8 "In3.Cu" signal "VCC1")
		(10 "In4.Cu" signal "GND1")
		(12 "In5.Cu" signal "IN1")
		(14 "In6.Cu" signal "GND2")
		(16 "In7.Cu" signal "IN2")
		(18 "In8.Cu" signal "GND3")
		(20 "In9.Cu" signal "IN3")
		(22 "In10.Cu" signal "GND4")
		(24 "In11.Cu" signal "IN4")
		(26 "In12.Cu" signal "GND5")
		(28 "In13.Cu" signal "IN5")
		(30 "In14.Cu" signal "GND6")
		(32 "In15.Cu" signal "IN6")
		(34 "In16.Cu" signal "GND7")
		(2 "B.Cu" signal "BOTTOM")
		(9 "F.Adhes" user "F.Adhesive")
		(11 "B.Adhes" user "B.Adhesive")
		(13 "F.Paste" user "Package Geometry/Pastemask Top")
		(15 "B.Paste" user "Package Geometry/Pastemask Bottom")
		(5 "F.SilkS" user "Ref Des/Silkscreen Top")
		(7 "B.SilkS" user "Ref Des/Silkscreen Bottom")
		(1 "F.Mask" user "Board Geometry/Soldermask Top")
		(3 "B.Mask" user "Board Geometry/Soldermask Bottom")
		(17 "Dwgs.User" user "User.Drawings")
		(19 "Cmts.User" user "User.Comments")
		(21 "Eco1.User" user "User.Eco1")
		(23 "Eco2.User" user "User.Eco2")
		(25 "Edge.Cuts" user "Board Geometry/Outline")
		(27 "Margin" user)
		(31 "F.CrtYd" user "Package Geometry/Place Bound Top")
		(29 "B.CrtYd" user "Package Geometry/Place Bound Bottom")
		(35 "F.Fab" user "Ref Des/Assembly Top")
		(33 "B.Fab" user "Ref Des/Assembly Bottom")
	)
	(footprint ""
		(layer "F.Cu")
		(at 80.915002 -343.952322 90)
		(property "Reference" "C146"
			(at 0 0 90)
			(layer "F.SilkS")
			(hide yes)
			(effects
				(font
					(size 1.27 1.27)
				)
			)
		)
		(property "Value" ""
			(at 0 0 90)
			(layer "F.Fab")
			(effects
				(font
					(size 1.27 1.27)
				)
			)
		)
		(duplicate_pad_numbers_are_jumpers no)
		(fp_line
			(start 0.299974 -0.150114)
			(end 0.299974 0.150114)
			(stroke
				(width 0.1)
				(type default)
			)
			(layer "F.Fab")
		)
		(fp_line
			(start -0.299974 -0.150114)
			(end 0.299974 -0.150114)
			(stroke
				(width 0.1)
				(type default)
			)
			(layer "F.Fab")
		)
		(fp_line
			(start 0.299974 0.150114)
			(end -0.299974 0.150114)
			(stroke
				(width 0.1)
				(type default)
			)
			(layer "F.Fab")
		)
		(fp_line
			(start -0.299974 0.150114)
			(end -0.299974 -0.150114)
			(stroke
				(width 0.1)
				(type default)
			)
			(layer "F.Fab")
		)
		(pad "1" smd rect
			(at -0.2667 0 90)
			(size 0.3048 0.381)
			(layers "F.Cu" "F.Mask" "F.Paste")
			(net "P5E_PEX0_STN6_TX_DN<103>")
		)
		(pad "2" smd rect
			(at 0.2667 0 90)
			(size 0.3048 0.381)
			(layers "F.Cu" "F.Mask" "F.Paste")
			(net "P5E_PEX0_STN6_TX_C_DN<103>")
		)
	)
	(footprint ""
		(layer "F.Cu")
		(at 89.498424 -297.46448)
		(property "Reference" "R3873"
			(at 0 0 0)
			(layer "F.SilkS")
			(hide yes)
			(effects
				(font
					(size 1.27 1.27)
				)
			)
		)
		(property "Value" ""
			(at 0 0 0)
			(layer "F.Fab")
			(effects
				(font
					(size 1.27 1.27)
				)
			)
		)
		(duplicate_pad_numbers_are_jumpers no)
		(fp_line
			(start -0.7874 -0.4064)
			(end 0.7874 -0.4064)
			(stroke
				(width 0.1524)
				(type default)
			)
			(layer "F.SilkS")
		)
		(fp_line
			(start -0.7874 0.4064)
			(end -0.7874 -0.4064)
			(stroke
				(width 0.1524)
				(type default)
			)
			(layer "F.SilkS")
		)
		(fp_line
			(start 0.7874 -0.4064)
			(end 0.7874 0.4064)
			(stroke
				(width 0.1524)
				(type default)
			)
			(layer "F.SilkS")
		)
		(fp_line
			(start 0.7874 0.4064)
			(end -0.7874 0.4064)
			(stroke
				(width 0.1524)
				(type default)
			)
			(layer "F.SilkS")
		)
		(fp_line
			(start -0.67945 -0.305054)
			(end -0.12065 -0.305054)
			(stroke
				(width 0.1)
				(type default)
			)
			(layer "F.Fab")
		)
		(fp_line
			(start -0.67945 0.3048)
			(end -0.67945 -0.305054)
			(stroke
				(width 0.1)
				(type default)
			)
			(layer "F.Fab")
		)
		(fp_line
			(start -0.12065 -0.305054)
			(end -0.12065 -0.2794)
			(stroke
				(width 0.1)
				(type default)
			)
			(layer "F.Fab")
		)
		(fp_line
			(start -0.12065 -0.2794)
			(end 0.12065 -0.2794)
			(stroke
				(width 0.1)
				(type default)
			)
			(layer "F.Fab")
		)
		(fp_line
			(start -0.12065 0.2794)
			(end -0.12065 0.3048)
			(stroke
				(width 0.1)
				(type default)
			)
			(layer "F.Fab")
		)
		(fp_line
			(start -0.12065 0.3048)
			(end -0.67945 0.3048)
			(stroke
				(width 0.1)
				(type default)
			)
			(layer "F.Fab")
		)
		(fp_line
			(start 0.120396 0.2794)
			(end -0.12065 0.2794)
			(stroke
				(width 0.1)
				(type default)
			)
			(layer "F.Fab")
		)
		(fp_line
			(start 0.120396 0.3048)
			(end 0.120396 0.2794)
			(stroke
				(width 0.1)
				(type default)
			)
			(layer "F.Fab")
		)
		(fp_line
			(start 0.12065 -0.3048)
			(end 0.67945 -0.3048)
			(stroke
				(width 0.1)
				(type default)
			)
			(layer "F.Fab")
		)
		(fp_line
			(start 0.12065 -0.2794)
			(end 0.12065 -0.3048)
			(stroke
				(width 0.1)
				(type default)
			)
			(layer "F.Fab")
		)
		(fp_line
			(start 0.67945 -0.3048)
			(end 0.67945 0.3048)
			(stroke
				(width 0.1)
				(type default)
			)
			(layer "F.Fab")
		)
		(fp_line
			(start 0.67945 0.3048)
			(end 0.120396 0.3048)
			(stroke
				(width 0.1)
				(type default)
			)
			(layer "F.Fab")
		)
		(pad "1" smd circle
			(at -0.40005 0)
			(size 0 0)
			(layers "F.Cu" "F.Mask" "F.Paste")
			(net "SMB_PEX0_HOST_LS_SDA")
		)
		(pad "2" smd circle
			(at 0.40005 0)
			(size 0 0)
			(layers "F.Cu" "F.Mask" "F.Paste")
			(net "I2C_PEX0_HOST_R_SDA")
		)
	)
	(footprint ""
		(layer "F.Cu")
		(at 33.287716 -282.018232)
		(property "Reference" "C3067"
			(at 0 0 0)
			(layer "F.SilkS")
			(hide yes)
			(effects
				(font
					(size 1.27 1.27)
				)
			)
		)
		(property "Value" ""
			(at 0 0 0)
			(layer "F.Fab")
			(effects
				(font
					(size 1.27 1.27)
				)
			)
		)
		(duplicate_pad_numbers_are_jumpers no)
		(fp_line
			(start -1.2954 -0.5842)
			(end 1.2954 -0.5842)
			(stroke
				(width 0.1524)
				(type default)
			)
			(layer "F.SilkS")
		)
		(fp_line
			(start -1.2954 0.5842)
			(end -1.2954 -0.5842)
			(stroke
				(width 0.1524)
				(type default)
			)
			(layer "F.SilkS")
		)
		(fp_line
			(start 1.2954 -0.5842)
			(end 1.2954 0.5842)
			(stroke
				(width 0.1524)
				(type default)
			)
			(layer "F.SilkS")
		)
		(fp_line
			(start 1.2954 0.5842)
			(end -1.2954 0.5842)
			(stroke
				(width 0.1524)
				(type default)
			)
			(layer "F.SilkS")
		)
		(fp_line
			(start -1.1938 -0.4064)
			(end -0.8636 -0.4064)
			(stroke
				(width 0.1)
				(type default)
			)
			(layer "F.Fab")
		)
		(fp_line
			(start -1.1938 0.4064)
			(end -1.1938 -0.4064)
			(stroke
				(width 0.1)
				(type default)
			)
			(layer "F.Fab")
		)
		(fp_line
			(start -0.8636 -0.4572)
			(end 0.8636 -0.4572)
			(stroke
				(width 0.1)
				(type default)
			)
			(layer "F.Fab")
		)
		(fp_line
			(start -0.8636 -0.4064)
			(end -0.8636 -0.4572)
			(stroke
				(width 0.1)
				(type default)
			)
			(layer "F.Fab")
		)
		(fp_line
			(start -0.8636 0.4064)
			(end -1.1938 0.4064)
			(stroke
				(width 0.1)
				(type default)
			)
			(layer "F.Fab")
		)
		(fp_line
			(start -0.8636 0.4572)
			(end -0.8636 0.4064)
			(stroke
				(width 0.1)
				(type default)
			)
			(layer "F.Fab")
		)
		(fp_line
			(start 0.8636 -0.4572)
			(end 0.8636 -0.4064)
			(stroke
				(width 0.1)
				(type default)
			)
			(layer "F.Fab")
		)
		(fp_line
			(start 0.8636 -0.4064)
			(end 1.1938 -0.4064)
			(stroke
				(width 0.1)
				(type default)
			)
			(layer "F.Fab")
		)
		(fp_line
			(start 0.8636 0.4064)
			(end 0.8636 0.4572)
			(stroke
				(width 0.1)
				(type default)
			)
			(layer "F.Fab")
		)
		(fp_line
			(start 0.8636 0.4572)
			(end -0.8636 0.4572)
			(stroke
				(width 0.1)
				(type default)
			)
			(layer "F.Fab")
		)
		(fp_line
			(start 1.1938 -0.4064)
			(end 1.1938 0.4064)
			(stroke
				(width 0.1)
				(type default)
			)
			(layer "F.Fab")
		)
		(fp_line
			(start 1.1938 0.4064)
			(end 0.8636 0.4064)
			(stroke
				(width 0.1)
				(type default)
			)
			(layer "F.Fab")
		)
		(pad "1" smd rect
			(at -0.7366 0 270)
			(size 0.7112 0.8128)
			(layers "F.Cu" "F.Mask" "F.Paste")
			(net "SYSPLL_VDDA18_PEX0")
		)
		(pad "2" smd rect
			(at 0.7366 0 270)
			(size 0.7112 0.8128)
			(layers "F.Cu" "F.Mask" "F.Paste")
			(net "GND")
		)
	)
	(footprint ""
		(layer "F.Cu")
		(at 449.145914 -46.4439 180)
		(property "Reference" "U78"
			(at 0.480314 -2.45237 0)
			(unlocked yes)
			(layer "F.SilkS")
			(effects
				(font
					(size 0.7874 0.5842)
					(thickness 0.1524)
				)
			)
		)
		(property "Value" ""
			(at 0 0 180)
			(layer "F.Fab")
			(effects
				(font
					(size 1.27 1.27)
				)
			)
		)
		(duplicate_pad_numbers_are_jumpers no)
		(fp_line
			(start 1.500124 1.500124)
			(end 1.004062 1.500124)
			(stroke
				(width 0.1524)
				(type default)
			)
			(layer "F.SilkS")
		)
		(fp_line
			(start 1.500124 1.004062)
			(end 1.500124 1.500124)
			(stroke
				(width 0.1524)
				(type default)
			)
			(layer "F.SilkS")
		)
		(fp_line
			(start 1.500124 -1.500124)
			(end 1.500124 -1.004062)
			(stroke
				(width 0.1524)
				(type default)
			)
			(layer "F.SilkS")
		)
		(fp_line
			(start 1.004062 -1.500124)
			(end 1.500124 -1.500124)
			(stroke
				(width 0.1524)
				(type default)
			)
			(layer "F.SilkS")
		)
		(fp_line
			(start -1.004062 1.500124)
			(end -1.500124 1.500124)
			(stroke
				(width 0.1524)
				(type default)
			)
			(layer "F.SilkS")
		)
		(fp_line
			(start -1.500124 1.500124)
			(end -1.500124 1.004062)
			(stroke
				(width 0.1524)
				(type default)
			)
			(layer "F.SilkS")
		)
		(fp_line
			(start -1.500124 -1.004062)
			(end -1.500124 -1.500124)
			(stroke
				(width 0.1524)
				(type default)
			)
			(layer "F.SilkS")
		)
		(fp_line
			(start -1.500124 -1.500124)
			(end -1.004062 -1.500124)
			(stroke
				(width 0.1524)
				(type default)
			)
			(layer "F.SilkS")
		)
		(fp_poly
			(pts
				(xy -1.903222 -2.34188) (xy -2.621788 -1.623568) (xy -1.544066 -1.264412)
			)
			(stroke
				(width 0)
				(type default)
			)
			(fill yes)
			(layer "F.SilkS")
		)
		(fp_line
			(start 1.500124 1.500124)
			(end -1.500124 1.500124)
			(stroke
				(width 0.1)
				(type default)
			)
			(layer "F.Fab")
		)
		(fp_line
			(start 1.500124 -1.500124)
			(end 1.500124 1.500124)
			(stroke
				(width 0.1)
				(type default)
			)
			(layer "F.Fab")
		)
		(fp_line
			(start -1.500124 1.500124)
			(end -1.500124 -1.500124)
			(stroke
				(width 0.1)
				(type default)
			)
			(layer "F.Fab")
		)
		(fp_line
			(start -1.500124 -1.500124)
			(end 1.500124 -1.500124)
			(stroke
				(width 0.1)
				(type default)
			)
			(layer "F.Fab")
		)
		(fp_poly
			(pts
				(xy -2.847848 -1.258062) (xy -2.847848 -0.242062) (xy -1.831848 -0.750062)
			)
			(stroke
				(width 0)
				(type default)
			)
			(fill yes)
			(layer "F.Fab")
		)
		(pad "1" smd rect
			(at -1.400048 -0.750062 90)
			(size 0.2286 0.6096)
			(layers "F.Cu" "F.Mask" "F.Paste")
			(net "SSD15_ADC_A1")
		)
		(pad "2" smd rect
			(at -1.400048 -0.249936 90)
			(size 0.2286 0.6096)
			(layers "F.Cu" "F.Mask" "F.Paste")
			(net "SSD15_ADC_A0")
		)
		(pad "3" smd rect
			(at -1.400048 0.249936 90)
			(size 0.2286 0.6096)
			(layers "F.Cu" "F.Mask" "F.Paste")
			(net "SSD15_ADC_ALERT_N")
		)
		(pad "4" smd rect
			(at -1.400048 0.750062 90)
			(size 0.2286 0.6096)
			(layers "F.Cu" "F.Mask" "F.Paste")
			(net "SMB_SSD15_ADC_SDA")
		)
		(pad "5" smd rect
			(at -0.750062 1.400048 180)
			(size 0.2286 0.6096)
			(layers "F.Cu" "F.Mask" "F.Paste")
			(net "SMB_SSD15_ADC_SCL")
		)
		(pad "6" smd rect
			(at -0.249936 1.400048 180)
			(size 0.2286 0.6096)
			(layers "F.Cu" "F.Mask" "F.Paste")
			(net "Net_8672")
		)
		(pad "7" smd rect
			(at 0.249936 1.400048 180)
			(size 0.2286 0.6096)
			(layers "F.Cu" "F.Mask" "F.Paste")
			(net "Net_8671")
		)
		(pad "8" smd rect
			(at 0.750062 1.400048 180)
			(size 0.2286 0.6096)
			(layers "F.Cu" "F.Mask" "F.Paste")
			(net "Net_8670")
		)
		(pad "9" smd rect
			(at 1.400048 0.750062 90)
			(size 0.2286 0.6096)
			(layers "F.Cu" "F.Mask" "F.Paste")
			(net "P3V3_AUX")
		)
		(pad "10" smd rect
			(at 1.400048 0.249936 90)
			(size 0.2286 0.6096)
			(layers "F.Cu" "F.Mask" "F.Paste")
			(net "GND")
		)
		(pad "11" smd rect
			(at 1.400048 -0.249936 90)
			(size 0.2286 0.6096)
			(layers "F.Cu" "F.Mask" "F.Paste")
			(net "P12V_SSD15_R")
		)
		(pad "12" smd rect
			(at 1.400048 -0.750062 90)
			(size 0.2286 0.6096)
			(layers "F.Cu" "F.Mask" "F.Paste")
			(net "P12V_SSD15_VIN_N")
		)
		(pad "13" smd rect
			(at 0.750062 -1.400048 180)
			(size 0.2286 0.6096)
			(layers "F.Cu" "F.Mask" "F.Paste")
			(net "P12V_SSD15_VIN_P")
		)
		(pad "14" smd rect
			(at 0.249936 -1.400048 180)
			(size 0.2286 0.6096)
			(layers "F.Cu" "F.Mask" "F.Paste")
			(net "Net_8669")
		)
		(pad "15" smd rect
			(at -0.249936 -1.400048 180)
			(size 0.2286 0.6096)
			(layers "F.Cu" "F.Mask" "F.Paste")
			(net "Net_8668")
		)
		(pad "16" smd rect
			(at -0.750062 -1.400048 180)
			(size 0.2286 0.6096)
			(layers "F.Cu" "F.Mask" "F.Paste")
			(net "Net_8667")
		)
		(pad "TH" smd rect
			(at 0 0 180)
			(size 1.7018 1.7018)
			(layers "F.Cu" "F.Mask" "F.Paste")
			(net "GND")
		)
		(zone
			(layer "F.Cu")
			(hatch none 0.5)
			(connect_pads
				(clearance 0)
			)
			(min_thickness 0.25)
			(keepout
				(tracks not_allowed)
				(vias allowed)
				(pads allowed)
				(copperpour not_allowed)
				(footprints allowed)
			)
			(placement
				(enabled no)
				(sheetname "")
			)
			(fill
				(thermal_gap 0.5)
				(thermal_bridge_width 0.5)
				(island_removal_mode 0)
			)
			(polygon
				(pts
					(xy 450.190362 -46.4185) (xy 450.190362 -45.399452) (xy 448.101466 -45.399452) (xy 448.101466 -47.488348)
					(xy 450.190362 -47.488348) (xy 450.190362 -46.4439) (xy 450.047614 -46.4439) (xy 450.047614 -47.3456)
					(xy 448.244214 -47.3456) (xy 448.244214 -45.5422) (xy 450.047614 -45.5422) (xy 450.047614 -46.4185)
				)
			)
		)
	)
	(footprint ""
		(layer "F.Cu")
		(at 431.946812 -343.952322 90)
		(property "Reference" "C2460"
			(at 0 0 90)
			(layer "F.SilkS")
			(hide yes)
			(effects
				(font
					(size 1.27 1.27)
				)
			)
		)
		(property "Value" ""
			(at 0 0 90)
			(layer "F.Fab")
			(effects
				(font
					(size 1.27 1.27)
				)
			)
		)
		(duplicate_pad_numbers_are_jumpers no)
		(fp_line
			(start 0.299974 -0.150114)
			(end 0.299974 0.150114)
			(stroke
				(width 0.1)
				(type default)
			)
			(layer "F.Fab")
		)
		(fp_line
			(start -0.299974 -0.150114)
			(end 0.299974 -0.150114)
			(stroke
				(width 0.1)
				(type default)
			)
			(layer "F.Fab")
		)
		(fp_line
			(start 0.299974 0.150114)
			(end -0.299974 0.150114)
			(stroke
				(width 0.1)
				(type default)
			)
			(layer "F.Fab")
		)
		(fp_line
			(start -0.299974 0.150114)
			(end -0.299974 -0.150114)
			(stroke
				(width 0.1)
				(type default)
			)
			(layer "F.Fab")
		)
		(pad "1" smd rect
			(at -0.2667 0 90)
			(size 0.3048 0.381)
			(layers "F.Cu" "F.Mask" "F.Paste")
			(net "P5E_PEX3_STN4_TX_DN<69>")
		)
		(pad "2" smd rect
			(at 0.2667 0 90)
			(size 0.3048 0.381)
			(layers "F.Cu" "F.Mask" "F.Paste")
			(net "P5E_PEX3_STN4_TX_C_DN<69>")
		)
	)
	(footprint ""
		(layer "F.Cu")
		(at 405.201882 -32.849312 90)
		(property "Reference" "R5710"
			(at 0 0 90)
			(layer "F.SilkS")
			(hide yes)
			(effects
				(font
					(size 1.27 1.27)
				)
			)
		)
		(property "Value" ""
			(at 0 0 90)
			(layer "F.Fab")
			(effects
				(font
					(size 1.27 1.27)
				)
			)
		)
		(duplicate_pad_numbers_are_jumpers no)
		(fp_line
			(start 0.7874 -0.4064)
			(end 0.7874 0.4064)
			(stroke
				(width 0.1524)
				(type default)
			)
			(layer "F.SilkS")
		)
		(fp_line
			(start -0.7874 -0.4064)
			(end 0.7874 -0.4064)
			(stroke
				(width 0.1524)
				(type default)
			)
			(layer "F.SilkS")
		)
		(fp_line
			(start 0.7874 0.4064)
			(end -0.7874 0.4064)
			(stroke
				(width 0.1524)
				(type default)
			)
			(layer "F.SilkS")
		)
		(fp_line
			(start -0.7874 0.4064)
			(end -0.7874 -0.4064)
			(stroke
				(width 0.1524)
				(type default)
			)
			(layer "F.SilkS")
		)
		(fp_line
			(start -0.12065 -0.305054)
			(end -0.12065 -0.2794)
			(stroke
				(width 0.1)
				(type default)
			)
			(layer "F.Fab")
		)
		(fp_line
			(start -0.67945 -0.305054)
			(end -0.12065 -0.305054)
			(stroke
				(width 0.1)
				(type default)
			)
			(layer "F.Fab")
		)
		(fp_line
			(start 0.67945 -0.3048)
			(end 0.67945 0.3048)
			(stroke
				(width 0.1)
				(type default)
			)
			(layer "F.Fab")
		)
		(fp_line
			(start 0.12065 -0.3048)
			(end 0.67945 -0.3048)
			(stroke
				(width 0.1)
				(type default)
			)
			(layer "F.Fab")
		)
		(fp_line
			(start 0.12065 -0.2794)
			(end 0.12065 -0.3048)
			(stroke
				(width 0.1)
				(type default)
			)
			(layer "F.Fab")
		)
		(fp_line
			(start -0.12065 -0.2794)
			(end 0.12065 -0.2794)
			(stroke
				(width 0.1)
				(type default)
			)
			(layer "F.Fab")
		)
		(fp_line
			(start 0.120396 0.2794)
			(end -0.12065 0.2794)
			(stroke
				(width 0.1)
				(type default)
			)
			(layer "F.Fab")
		)
		(fp_line
			(start -0.12065 0.2794)
			(end -0.12065 0.3048)
			(stroke
				(width 0.1)
				(type default)
			)
			(layer "F.Fab")
		)
		(fp_line
			(start 0.67945 0.3048)
			(end 0.120396 0.3048)
			(stroke
				(width 0.1)
				(type default)
			)
			(layer "F.Fab")
		)
		(fp_line
			(start 0.120396 0.3048)
			(end 0.120396 0.2794)
			(stroke
				(width 0.1)
				(type default)
			)
			(layer "F.Fab")
		)
		(fp_line
			(start -0.12065 0.3048)
			(end -0.67945 0.3048)
			(stroke
				(width 0.1)
				(type default)
			)
			(layer "F.Fab")
		)
		(fp_line
			(start -0.67945 0.3048)
			(end -0.67945 -0.305054)
			(stroke
				(width 0.1)
				(type default)
			)
			(layer "F.Fab")
		)
		(pad "1" smd circle
			(at -0.40005 0 90)
			(size 0 0)
			(layers "F.Cu" "F.Mask" "F.Paste")
			(net "RST_SMB_SSD14_ISO_R_N")
		)
		(pad "2" smd circle
			(at 0.40005 0 90)
			(size 0 0)
			(layers "F.Cu" "F.Mask" "F.Paste")
			(net "RST_SMB_SSD14_ISO_N")
		)
	)
	(footprint ""
		(layer "F.Cu")
		(at 482.178868 -523.784322 180)
		(property "Reference" "SCREW_7"
			(at -3.2385 -1.402334 0)
			(unlocked yes)
			(layer "B.SilkS")
			(effects
				(font
					(size 0.7874 0.5842)
					(thickness 0.1524)
				)
				(justify mirror)
			)
		)
		(property "Value" ""
			(at 0 0 180)
			(layer "F.Fab")
			(effects
				(font
					(size 1.27 1.27)
				)
			)
		)
		(duplicate_pad_numbers_are_jumpers no)
		(pad "1" thru_hole circle
			(at 0 0 180)
			(size 0.4572 0.4572)
			(drill 0.2032)
			(layers "*.Cu" "*.Mask")
			(remove_unused_layers no)
			(net "Net_9157")
			(clearance 0.127)
			(thermal_gap 0.127)
			(padstack
				(mode front_inner_back)
				(layer "Inner"
					(shape circle)
					(size 0.4572 0.4572)
					(clearance 0.127)
				)
				(layer "B.Cu"
					(shape circle)
					(size 0.508 0.508)
					(clearance 0.1016)
				)
			)
		)
	)
	(footprint ""
		(layer "F.Cu")
		(at 448.799966 -84.699856)
		(property "Reference" "H70"
			(at -4.574794 -5.040884 0)
			(unlocked yes)
			(layer "F.SilkS")
			(effects
				(font
					(size 0.7874 0.5842)
					(thickness 0.1524)
				)
				(justify left)
			)
		)
		(property "Value" ""
			(at 0 0 0)
			(layer "F.Fab")
			(effects
				(font
					(size 1.27 1.27)
				)
			)
		)
		(duplicate_pad_numbers_are_jumpers no)
		(pad "1" thru_hole circle
			(at 0 0)
			(size 10.0076 10.0076)
			(drill 5.6134)
			(layers "*.Cu" "*.Mask")
			(remove_unused_layers no)
			(net "GND")
			(clearance -1.9431)
		)
	)
)
